(kicad_pcb
	(version 20260206)
	(generator "pcbnew")
	(generator_version "10.0")
	(general
		(thickness 1.6)
		(legacy_teardrops no)
	)
	(paper "A4")
	(title_block
		(title "Bryce Canyon_F.DPB_16315-1-OCP.brd")
		(comment 1 "Bryce Canyon / footprints 166-171 of 2223")
	)
	(layers
		(0 "F.Cu" signal "TOP")
		(4 "In1.Cu" signal "L2GND")
		(6 "In2.Cu" signal "L3")
		(8 "In3.Cu" signal "L4GND")
		(10 "In4.Cu" signal "L5")
		(12 "In5.Cu" signal "L6VCC")
		(14 "In6.Cu" signal "L7VCC")
		(16 "In7.Cu" signal "L8")
		(18 "In8.Cu" signal "L9GND")
		(20 "In9.Cu" signal "L10")
		(22 "In10.Cu" signal "L11GND")
		(2 "B.Cu" signal "BOTTOM")
		(9 "F.Adhes" user "F.Adhesive")
		(11 "B.Adhes" user "B.Adhesive")
		(13 "F.Paste" user "Package Geometry/Pastemask Top")
		(15 "B.Paste" user "Package Geometry/Pastemask Bottom")
		(5 "F.SilkS" user "Ref Des/Silkscreen Top")
		(7 "B.SilkS" user "Ref Des/Silkscreen Bottom")
		(1 "F.Mask" user "Board Geometry/Soldermask Top")
		(3 "B.Mask" user "Board Geometry/Soldermask Bottom")
		(17 "Dwgs.User" user "User.Drawings")
		(19 "Cmts.User" user "User.Comments")
		(21 "Eco1.User" user "User.Eco1")
		(23 "Eco2.User" user "User.Eco2")
		(25 "Edge.Cuts" user "Board Geometry/Outline")
		(27 "Margin" user)
		(31 "F.CrtYd" user "Package Geometry/Place Bound Top")
		(29 "B.CrtYd" user "Package Geometry/Place Bound Bottom")
		(35 "F.Fab" user "Ref Des/Assembly Top")
		(33 "B.Fab" user "Ref Des/Assembly Bottom")
	)
	(footprint ""
		(layer "F.Cu")
		(at 427.390052 -278.554942 -90)
		(property "Reference" "R344"
			(at 0 0 270)
			(layer "F.SilkS")
			(hide yes)
			(effects
				(font
					(size 1.27 1.27)
				)
			)
		)
		(property "Value" "4K7R2J-2-GP"
			(at 0.064008 -3.993896 270)
			(unlocked yes)
			(layer "F.Fab")
			(hide yes)
			(effects
				(font
					(size 1.016 1.016)
					(thickness 0.1524)
				)
			)
		)
		(property "Device Type" "R402H16"
			(at 0.064008 -5.517896 270)
			(unlocked yes)
			(layer "F.Fab")
			(hide yes)
			(effects
				(font
					(size 1.016 1.016)
					(thickness 0.1524)
				)
			)
		)
		(duplicate_pad_numbers_are_jumpers no)
		(fp_line
			(start -0.508 -0.9398)
			(end -0.508 0.9398)
			(stroke
				(width 0.1524)
				(type default)
			)
			(layer "F.SilkS")
		)
		(fp_line
			(start 0.508 -0.9398)
			(end -0.508 -0.9398)
			(stroke
				(width 0.1524)
				(type default)
			)
			(layer "F.SilkS")
		)
		(fp_rect
			(start -0.508 0.9398)
			(end 0.508 -0.9398)
			(stroke
				(width 0)
				(type default)
			)
			(fill no)
			(layer "F.CrtYd")
		)
		(fp_rect
			(start -0.508 0.9398)
			(end 0.508 -0.9398)
			(stroke
				(width 0)
				(type default)
			)
			(fill no)
			(layer "F.Fab")
		)
		(pad "1" smd custom
			(at 0 -0.4445 270)
			(size 0.1397 0.1397)
			(layers "F.Cu" "F.Mask" "F.Paste")
			(net "P12V_A")
			(options
				(clearance outline)
				(anchor circle)
			)
			(primitives
				(gr_poly
					(pts
						(arc
							(start -0.1778 -0.2794)
							(mid -0.249642 -0.249642)
							(end -0.2794 -0.1778)
						)
						(arc
							(start -0.2794 0.1778)
							(mid -0.249642 0.249642)
							(end -0.1778 0.2794)
						)
						(arc
							(start 0.1778 0.2794)
							(mid 0.249642 0.249642)
							(end 0.2794 0.1778)
						)
						(arc
							(start 0.2794 -0.1778)
							(mid 0.249642 -0.249642)
							(end 0.1778 -0.2794)
						)
					)
					(width 0)
					(fill yes)
				)
			)
		)
		(pad "2" smd custom
			(at 0 0.4445 270)
			(size 0.1397 0.1397)
			(layers "F.Cu" "F.Mask" "F.Paste")
			(net "SW_HDD_P9")
			(options
				(clearance outline)
				(anchor circle)
			)
			(primitives
				(gr_poly
					(pts
						(arc
							(start -0.1778 -0.2794)
							(mid -0.249642 -0.249642)
							(end -0.2794 -0.1778)
						)
						(arc
							(start -0.2794 0.1778)
							(mid -0.249642 0.249642)
							(end -0.1778 0.2794)
						)
						(arc
							(start 0.1778 0.2794)
							(mid 0.249642 0.249642)
							(end 0.2794 0.1778)
						)
						(arc
							(start 0.2794 -0.1778)
							(mid 0.249642 -0.249642)
							(end 0.1778 -0.2794)
						)
					)
					(width 0)
					(fill yes)
				)
			)
		)
	)
	(footprint ""
		(layer "F.Cu")
		(at 329.819 -296.842942 180)
		(property "Reference" "C118"
			(at 0 0 180)
			(layer "F.SilkS")
			(hide yes)
			(effects
				(font
					(size 1.27 1.27)
				)
			)
		)
		(property "Value" "SC1U16V3KX-5GP"
			(at 0 -2.8194 180)
			(unlocked yes)
			(layer "F.Fab")
			(hide yes)
			(effects
				(font
					(size 1.016 1.016)
					(thickness 0.1524)
				)
			)
		)
		(property "Device Type" "C603H36"
			(at 0 -4.3434 180)
			(unlocked yes)
			(layer "F.Fab")
			(hide yes)
			(effects
				(font
					(size 1.016 1.016)
					(thickness 0.1524)
				)
			)
		)
		(duplicate_pad_numbers_are_jumpers no)
		(fp_line
			(start 0.508 0)
			(end -0.508 0)
			(stroke
				(width 0.2032)
				(type default)
			)
			(layer "F.SilkS")
		)
		(fp_rect
			(start -0.5842 1.3335)
			(end 0.5842 -1.3335)
			(stroke
				(width 0)
				(type default)
			)
			(fill no)
			(layer "F.CrtYd")
		)
		(fp_rect
			(start -0.5842 1.3335)
			(end 0.5842 -1.3335)
			(stroke
				(width 0)
				(type default)
			)
			(fill no)
			(layer "F.Fab")
		)
		(pad "1" smd custom
			(at 0 -0.762 180)
			(size 0.2159 0.2159)
			(layers "F.Cu" "F.Mask" "F.Paste")
			(net "P5V_HDD6")
			(options
				(clearance outline)
				(anchor circle)
			)
			(primitives
				(gr_poly
					(pts
						(arc
							(start -0.3302 -0.4318)
							(mid -0.402042 -0.402042)
							(end -0.4318 -0.3302)
						)
						(arc
							(start -0.4318 0.3302)
							(mid -0.402042 0.402042)
							(end -0.3302 0.4318)
						)
						(arc
							(start 0.3302 0.4318)
							(mid 0.402042 0.402042)
							(end 0.4318 0.3302)
						)
						(arc
							(start 0.4318 -0.3302)
							(mid 0.402042 -0.402042)
							(end 0.3302 -0.4318)
						)
					)
					(width 0)
					(fill yes)
				)
			)
		)
		(pad "2" smd custom
			(at 0 0.762 180)
			(size 0.2159 0.2159)
			(layers "F.Cu" "F.Mask" "F.Paste")
			(net "GND")
			(options
				(clearance outline)
				(anchor circle)
			)
			(primitives
				(gr_poly
					(pts
						(arc
							(start -0.3302 -0.4318)
							(mid -0.402042 -0.402042)
							(end -0.4318 -0.3302)
						)
						(arc
							(start -0.4318 0.3302)
							(mid -0.402042 0.402042)
							(end -0.3302 0.4318)
						)
						(arc
							(start 0.3302 0.4318)
							(mid 0.402042 0.402042)
							(end 0.4318 0.3302)
						)
						(arc
							(start 0.4318 -0.3302)
							(mid 0.402042 -0.402042)
							(end 0.3302 -0.4318)
						)
					)
					(width 0)
					(fill yes)
				)
			)
		)
	)
	(footprint ""
		(layer "F.Cu")
		(at 175.550068 -324.39991)
		(property "Reference" "RLED30"
			(at 0 0 0)
			(layer "F.SilkS")
			(hide yes)
			(effects
				(font
					(size 1.27 1.27)
				)
			)
		)
		(property "Value" "LED-BY-19-GP"
			(at -2.132076 1.414018 0)
			(unlocked yes)
			(layer "F.Fab")
			(hide yes)
			(effects
				(font
					(size 1.016 1.016)
					(thickness 0.1524)
				)
			)
		)
		(property "Device Type" "LED-1615-4PH26"
			(at -2.132076 -0.109982 0)
			(unlocked yes)
			(layer "F.Fab")
			(hide yes)
			(effects
				(font
					(size 1.016 1.016)
					(thickness 0.1524)
				)
			)
		)
		(duplicate_pad_numbers_are_jumpers no)
		(fp_line
			(start -1.2954 0.254)
			(end -1.2954 1.6002)
			(stroke
				(width 0.508)
				(type default)
			)
			(layer "F.SilkS")
		)
		(fp_line
			(start -1.2954 1.6002)
			(end 1.2954 1.6002)
			(stroke
				(width 0.508)
				(type default)
			)
			(layer "F.SilkS")
		)
		(fp_line
			(start -1.1176 -1.4224)
			(end 1.1176 -1.4224)
			(stroke
				(width 0.1524)
				(type default)
			)
			(layer "F.SilkS")
		)
		(fp_line
			(start -1.1176 1.4224)
			(end -1.1176 -1.4224)
			(stroke
				(width 0.1524)
				(type default)
			)
			(layer "F.SilkS")
		)
		(fp_line
			(start 1.1176 -1.4224)
			(end 1.1176 1.4224)
			(stroke
				(width 0.1524)
				(type default)
			)
			(layer "F.SilkS")
		)
		(fp_line
			(start 1.1176 1.4224)
			(end -1.1176 1.4224)
			(stroke
				(width 0.1524)
				(type default)
			)
			(layer "F.SilkS")
		)
		(fp_line
			(start 1.2954 1.6002)
			(end 1.2954 0.254)
			(stroke
				(width 0.508)
				(type default)
			)
			(layer "F.SilkS")
		)
		(fp_rect
			(start -0.7493 0.8001)
			(end 0.7493 -0.8001)
			(stroke
				(width 0)
				(type default)
			)
			(fill no)
			(layer "F.CrtYd")
		)
		(fp_poly
			(pts
				(xy -1.3716 1.6764) (xy -1.3716 -1.6764) (xy 1.3716 -1.6764) (xy 1.3716 0.0635) (xy 0.7493 0.0635)
				(xy 0.7493 -0.8001) (xy -0.7493 -0.8001) (xy -0.7493 0.8001) (xy 0.7493 0.8001) (xy 0.7493 0.0762)
				(xy 1.3716 0.0762) (xy 1.3716 1.6764)
			)
			(stroke
				(width 0)
				(type default)
			)
			(fill no)
			(layer "F.CrtYd")
		)
		(fp_rect
			(start -1.3716 1.6764)
			(end 1.3716 -1.6764)
			(stroke
				(width 0)
				(type default)
			)
			(fill no)
			(layer "F.Fab")
		)
		(pad "1" smd rect
			(at 0.50038 -0.73025)
			(size 0.7112 0.8636)
			(layers "F.Cu" "F.Mask" "F.Paste")
			(net "DRV_ACT_29")
		)
		(pad "2" smd rect
			(at -0.50038 -0.73025)
			(size 0.7112 0.8636)
			(layers "F.Cu" "F.Mask" "F.Paste")
			(net "FLT_HDD29")
		)
		(pad "3" smd rect
			(at 0.50038 0.73025)
			(size 0.7112 0.8636)
			(layers "F.Cu" "F.Mask" "F.Paste")
			(net "DRV_ACT_29_N")
		)
		(pad "4" smd rect
			(at -0.50038 0.73025)
			(size 0.7112 0.8636)
			(layers "F.Cu" "F.Mask" "F.Paste")
			(net "FLT_HDD29_N")
		)
	)
	(footprint ""
		(layer "F.Cu")
		(at 263.238996 -344.049604 -90)
		(property "Reference" "R981"
			(at 0 0 270)
			(layer "F.SilkS")
			(hide yes)
			(effects
				(font
					(size 1.27 1.27)
				)
			)
		)
		(property "Value" "4K7R2F-GP"
			(at 0.064008 -3.993896 270)
			(unlocked yes)
			(layer "F.Fab")
			(hide yes)
			(effects
				(font
					(size 1.016 1.016)
					(thickness 0.1524)
				)
			)
		)
		(property "Device Type" "R402H16"
			(at 0.064008 -5.517896 270)
			(unlocked yes)
			(layer "F.Fab")
			(hide yes)
			(effects
				(font
					(size 1.016 1.016)
					(thickness 0.1524)
				)
			)
		)
		(duplicate_pad_numbers_are_jumpers no)
		(fp_line
			(start -0.508 -0.9398)
			(end -0.508 0.9398)
			(stroke
				(width 0.1524)
				(type default)
			)
			(layer "F.SilkS")
		)
		(fp_line
			(start 0.508 -0.9398)
			(end -0.508 -0.9398)
			(stroke
				(width 0.1524)
				(type default)
			)
			(layer "F.SilkS")
		)
		(fp_rect
			(start -0.508 0.9398)
			(end 0.508 -0.9398)
			(stroke
				(width 0)
				(type default)
			)
			(fill no)
			(layer "F.CrtYd")
		)
		(fp_rect
			(start -0.508 0.9398)
			(end 0.508 -0.9398)
			(stroke
				(width 0)
				(type default)
			)
			(fill no)
			(layer "F.Fab")
		)
		(pad "1" smd custom
			(at 0 -0.4445 270)
			(size 0.1397 0.1397)
			(layers "F.Cu" "F.Mask" "F.Paste")
			(net "SCC_A_SLOT_ID_1")
			(options
				(clearance outline)
				(anchor circle)
			)
			(primitives
				(gr_poly
					(pts
						(arc
							(start -0.1778 -0.2794)
							(mid -0.249642 -0.249642)
							(end -0.2794 -0.1778)
						)
						(arc
							(start -0.2794 0.1778)
							(mid -0.249642 0.249642)
							(end -0.1778 0.2794)
						)
						(arc
							(start 0.1778 0.2794)
							(mid 0.249642 0.249642)
							(end 0.2794 0.1778)
						)
						(arc
							(start 0.2794 -0.1778)
							(mid 0.249642 -0.249642)
							(end 0.1778 -0.2794)
						)
					)
					(width 0)
					(fill yes)
				)
			)
		)
		(pad "2" smd custom
			(at 0 0.4445 270)
			(size 0.1397 0.1397)
			(layers "F.Cu" "F.Mask" "F.Paste")
			(net "GND")
			(options
				(clearance outline)
				(anchor circle)
			)
			(primitives
				(gr_poly
					(pts
						(arc
							(start -0.1778 -0.2794)
							(mid -0.249642 -0.249642)
							(end -0.2794 -0.1778)
						)
						(arc
							(start -0.2794 0.1778)
							(mid -0.249642 0.249642)
							(end -0.1778 0.2794)
						)
						(arc
							(start 0.1778 0.2794)
							(mid 0.249642 0.249642)
							(end 0.2794 0.1778)
						)
						(arc
							(start 0.2794 -0.1778)
							(mid 0.249642 -0.249642)
							(end 0.1778 -0.2794)
						)
					)
					(width 0)
					(fill yes)
				)
			)
		)
	)
	(footprint ""
		(layer "F.Cu")
		(at 314.356496 -130.411728 -90)
		(property "Reference" "R526"
			(at 0 0 270)
			(layer "F.SilkS")
			(hide yes)
			(effects
				(font
					(size 1.27 1.27)
				)
			)
		)
		(property "Value" "4K7R2J-2-GP"
			(at 0.064008 -3.993896 270)
			(unlocked yes)
			(layer "F.Fab")
			(hide yes)
			(effects
				(font
					(size 1.016 1.016)
					(thickness 0.1524)
				)
			)
		)
		(property "Device Type" "R402H16"
			(at 0.064008 -5.517896 270)
			(unlocked yes)
			(layer "F.Fab")
			(hide yes)
			(effects
				(font
					(size 1.016 1.016)
					(thickness 0.1524)
				)
			)
		)
		(duplicate_pad_numbers_are_jumpers no)
		(fp_line
			(start -0.508 -0.9398)
			(end -0.508 0.9398)
			(stroke
				(width 0.1524)
				(type default)
			)
			(layer "F.SilkS")
		)
		(fp_line
			(start 0.508 -0.9398)
			(end -0.508 -0.9398)
			(stroke
				(width 0.1524)
				(type default)
			)
			(layer "F.SilkS")
		)
		(fp_rect
			(start -0.508 0.9398)
			(end 0.508 -0.9398)
			(stroke
				(width 0)
				(type default)
			)
			(fill no)
			(layer "F.CrtYd")
		)
		(fp_rect
			(start -0.508 0.9398)
			(end 0.508 -0.9398)
			(stroke
				(width 0)
				(type default)
			)
			(fill no)
			(layer "F.Fab")
		)
		(pad "1" smd custom
			(at 0 -0.4445 270)
			(size 0.1397 0.1397)
			(layers "F.Cu" "F.Mask" "F.Paste")
			(net "DRIVE_A_18_ACT")
			(options
				(clearance outline)
				(anchor circle)
			)
			(primitives
				(gr_poly
					(pts
						(arc
							(start -0.1778 -0.2794)
							(mid -0.249642 -0.249642)
							(end -0.2794 -0.1778)
						)
						(arc
							(start -0.2794 0.1778)
							(mid -0.249642 0.249642)
							(end -0.1778 0.2794)
						)
						(arc
							(start 0.1778 0.2794)
							(mid 0.249642 0.249642)
							(end 0.2794 0.1778)
						)
						(arc
							(start 0.2794 -0.1778)
							(mid 0.249642 -0.249642)
							(end 0.1778 -0.2794)
						)
					)
					(width 0)
					(fill yes)
				)
			)
		)
		(pad "2" smd custom
			(at 0 0.4445 270)
			(size 0.1397 0.1397)
			(layers "F.Cu" "F.Mask" "F.Paste")
			(net "GND")
			(options
				(clearance outline)
				(anchor circle)
			)
			(primitives
				(gr_poly
					(pts
						(arc
							(start -0.1778 -0.2794)
							(mid -0.249642 -0.249642)
							(end -0.2794 -0.1778)
						)
						(arc
							(start -0.2794 0.1778)
							(mid -0.249642 0.249642)
							(end -0.1778 0.2794)
						)
						(arc
							(start 0.1778 0.2794)
							(mid 0.249642 0.249642)
							(end 0.2794 0.1778)
						)
						(arc
							(start 0.2794 -0.1778)
							(mid 0.249642 -0.249642)
							(end 0.1778 -0.2794)
						)
					)
					(width 0)
					(fill yes)
				)
			)
		)
	)
	(footprint ""
		(layer "F.Cu")
		(at 471.275918 -159.088074 90)
		(property "Reference" "Q139"
			(at 0 0 90)
			(layer "F.SilkS")
			(hide yes)
			(effects
				(font
					(size 1.27 1.27)
				)
			)
		)
		(property "Value" "2N7002KDW-GP"
			(at -2.3622 -8.2042 90)
			(unlocked yes)
			(layer "F.Fab")
			(hide yes)
			(effects
				(font
					(size 1.016 1.016)
					(thickness 0.1524)
				)
			)
		)
		(property "Device Type" "SOT-363H44"
			(at -2.3622 -10.1092 90)
			(unlocked yes)
			(layer "F.Fab")
			(hide yes)
			(effects
				(font
					(size 1.016 1.016)
					(thickness 0.1524)
				)
			)
		)
		(duplicate_pad_numbers_are_jumpers no)
		(fp_line
			(start 1.4478 -1.7018)
			(end -1.4478 -1.7018)
			(stroke
				(width 0.1524)
				(type default)
			)
			(layer "F.SilkS")
		)
		(fp_line
			(start -1.4478 -1.7018)
			(end -1.4478 1.7018)
			(stroke
				(width 0.1524)
				(type default)
			)
			(layer "F.SilkS")
		)
		(fp_line
			(start -1.27 1.524)
			(end -1.27 0.6604)
			(stroke
				(width 0.4826)
				(type default)
			)
			(layer "F.SilkS")
		)
		(fp_line
			(start 1.4478 1.7018)
			(end 1.4478 -1.7018)
			(stroke
				(width 0.1524)
				(type default)
			)
			(layer "F.SilkS")
		)
		(fp_line
			(start -1.4478 1.7018)
			(end 1.4478 1.7018)
			(stroke
				(width 0.1524)
				(type default)
			)
			(layer "F.SilkS")
		)
		(fp_poly
			(pts
				(xy -1.524 -1.778) (xy 1.524 -1.778) (xy 1.524 1.778) (xy -1.524 1.778)
			)
			(stroke
				(width 0)
				(type default)
			)
			(fill no)
			(layer "F.CrtYd")
		)
		(fp_poly
			(pts
				(xy -1.524 -1.778) (xy 1.524 -1.778) (xy 1.524 1.778) (xy -1.524 1.778)
			)
			(stroke
				(width 0)
				(type default)
			)
			(fill no)
			(layer "F.Fab")
		)
		(pad "1" smd rect
			(at -0.65024 0.9398 90)
			(size 0.4064 1.016)
			(layers "F.Cu" "F.Mask" "F.Paste")
			(net "GND")
		)
		(pad "2" smd rect
			(at 0 0.9398 90)
			(size 0.4064 1.016)
			(layers "F.Cu" "F.Mask" "F.Paste")
			(net "SW_PWR_R_HDD23")
		)
		(pad "3" smd rect
			(at 0.65024 0.9398 90)
			(size 0.4064 1.016)
			(layers "F.Cu" "F.Mask" "F.Paste")
			(net "SW_HDD_P23")
		)
		(pad "4" smd rect
			(at 0.65024 -0.9398 90)
			(size 0.4064 1.016)
			(layers "F.Cu" "F.Mask" "F.Paste")
			(net "GND")
		)
		(pad "5" smd rect
			(at 0 -0.9398 90)
			(size 0.4064 1.016)
			(layers "F.Cu" "F.Mask" "F.Paste")
			(net "SW_HDD_G23")
		)
		(pad "6" smd rect
			(at -0.65024 -0.9398 90)
			(size 0.4064 1.016)
			(layers "F.Cu" "F.Mask" "F.Paste")
			(net "SW_HDD_R23")
		)
	)
)
